# T6G (Grand Teton) — schematic netlist excerpt (pin names and nets, part order shuffled) for the footprints in the layout excerpt that follows; sources: Cadence DE-HDL packaged netlist, KiCad conversion of 04192023_DAF0TMB3IC0_F0TG_MB_C_brd_V02_OCP.brd

J67  SCONN288_DDR506112002KQ  IO  pkg DDR288S_1-1VXC  page 97
  VIN_BULK0  = P12V_MEM_CPU0
  RFU0  = NC
  VIN_MGMT  = P3V3_AUX
  HSCL  = I3C_SPD_DDRL_CPU0_SCL
  HSDA  = I3C_SPD_DDRL_CPU0_SDA
  VSS0  = GND
  DQ0_A  = M_L_CPU0_SA_DQ<0>
  VSS1  = GND
  DQ1_A  = M_L_CPU0_SA_DQ<1>
  VSS2  = GND
  DQS0_A_T  = M_L_CPU0_SA_DQS_DP<0>
  DQS0_A_C  = M_L_CPU0_SA_DQS_DN<0>
  VSS3  = GND
  DQ4_A  = M_L_CPU0_SA_DQ<4>
  VSS4  = GND
  DQ5_A  = M_L_CPU0_SA_DQ<5>
  VSS5  = GND
  DQ8_A  = M_L_CPU0_SA_DQ<8>
  VSS6  = GND
  DQ9_A  = M_L_CPU0_SA_DQ<9>
  VSS7  = GND
  DQS1_A_T  = M_L_CPU0_SA_DQS_DP<1>
  DQS1_A_C  = M_L_CPU0_SA_DQS_DN<1>
  VSS8  = GND
  DQ12_A  = M_L_CPU0_SA_DQ<12>
  VSS9  = GND
  DQ13_A  = M_L_CPU0_SA_DQ<13>
  VSS10  = GND
  DQ16_A  = M_L_CPU0_SA_DQ<16>
  VSS11  = GND
  DQ17_A  = M_L_CPU0_SA_DQ<17>
  VSS12  = GND
  DQS2_A_T  = M_L_CPU0_SA_DQS_DP<2>
  DQS2_A_C  = M_L_CPU0_SA_DQS_DN<2>
  VSS13  = GND
  DQ20_A  = M_L_CPU0_SA_DQ<20>
  VSS14  = GND
  DQ21_A  = M_L_CPU0_SA_DQ<21>
  VSS15  = GND
  DQ24_A  = M_L_CPU0_SA_DQ<24>
  VSS16  = GND
  DQ25_A  = M_L_CPU0_SA_DQ<25>
  VSS17  = GND
  DQS3_A_T  = M_L_CPU0_SA_DQS_DP<3>
  DQS3_A_C  = M_L_CPU0_SA_DQS_DN<3>
  VSS18  = GND
  DQ28_A  = M_L_CPU0_SA_DQ<28>
  VSS19  = GND
  DQ29_A  = M_L_CPU0_SA_DQ<29>
  VSS20  = GND
  CB0_A  = M_L_CPU0_SA_CB<0>
  VSS21  = GND
  CB1_A  = M_L_CPU0_SA_CB<1>
  VSS22  = GND
  DQS4_A_T  = M_L_CPU0_SA_DQS_DP<4>
  DQS4_A_C  = M_L_CPU0_SA_DQS_DN<4>
  VSS23  = GND
  CB4_A  = M_L_CPU0_SA_CB<4>
  VSS24  = GND
  CB5_A  = M_L_CPU0_SA_CB<5>
  VSS25  = GND
  ALERT_N  = M_L_CPU0_ALERT_N
  VSS26  = GND
  CS0_A_N  = M_L_CPU0_SA_CS_N<0>
  VSS27  = GND
  CA0_A  = M_L_CPU0_SA_CA<0>
  VSS28  = GND
  CA2_A  = M_L_CPU0_SA_CA<2>
  VSS29  = GND
  CA4_A  = M_L_CPU0_SA_CA<4>
  VSS30  = GND
  CA6_A  = M_L_CPU0_SA_CA<6>
  VSS31  = GND
  PAR_A  = M_L_CPU0_SA_PAR
  VSS32  = GND
  CA0_B  = M_L_CPU0_SB_CA<0>
  VSS33  = GND
  CA2_B  = M_L_CPU0_SB_CA<2>
  VSS34  = GND
  CA4_B  = M_L_CPU0_SB_CA<4>
  VSS35  = GND
  CA6_B  = M_L_CPU0_SB_CA<6>
  VSS36  = GND
  CS0_B_N  = M_L_CPU0_SB_CS_N<0>
  VSS37  = GND
  \lbd||rsp_a_n\  = M_L_CPU0_SA_RSP<0>
  \lbs||rsp_b_n\  = M_L_CPU0_SB_RSP<0>
  VSS38  = GND
  CB4_B  = M_L_CPU0_SB_CB<4>
  VSS39  = GND
  CB5_B  = M_L_CPU0_SB_CB<5>
  VSS40  = GND
  \dqs9_b_t||tdqs9_b_t||dbi4_b_n\  = M_L_CPU0_SB_DQS_DP<9>
  \dqs9_b_c||tdqs9_b_c\  = M_L_CPU0_SB_DQS_DN<9>
  VSS41  = GND
  CB0_B  = M_L_CPU0_SB_CB<0>
  VSS42  = GND
  CB1_B  = M_L_CPU0_SB_CB<1>
  VSS43  = GND
  DQ0_B  = M_L_CPU0_SB_DQ<0>
  VSS44  = GND
  DQ1_B  = M_L_CPU0_SB_DQ<1>
  VSS45  = GND
  DQS0_B_T  = M_L_CPU0_SB_DQS_DP<0>
  DQS0_B_C  = M_L_CPU0_SB_DQS_DN<0>
  VSS46  = GND
  DQ4_B  = M_L_CPU0_SB_DQ<4>
  VSS47  = GND
  DQ5_B  = M_L_CPU0_SB_DQ<5>
  VSS48  = GND
  DQ8_B  = M_L_CPU0_SB_DQ<8>
  VSS49  = GND
  DQ9_B  = M_L_CPU0_SB_DQ<9>
  VSS50  = GND
  DQS1_B_T  = M_L_CPU0_SB_DQS_DP<1>
  DQS1_B_C  = M_L_CPU0_SB_DQS_DN<1>
  VSS51  = GND
  DQ12_B  = M_L_CPU0_SB_DQ<12>
  VSS52  = GND
  DQ13_B  = M_L_CPU0_SB_DQ<13>
  VSS53  = GND
  DQ16_B  = M_L_CPU0_SB_DQ<16>
  VSS54  = GND
  DQ17_B  = M_L_CPU0_SB_DQ<17>
  VSS55  = GND
  DQS2_B_T  = M_L_CPU0_SB_DQS_DP<2>
  DQS2_B_C  = M_L_CPU0_SB_DQS_DN<2>
  VSS56  = GND
  DQ20_B  = M_L_CPU0_SB_DQ<20>
  VSS57  = GND
  DQ21_B  = M_L_CPU0_SB_DQ<21>
  VSS58  = GND
  DQ24_B  = M_L_CPU0_SB_DQ<24>
  VSS59  = GND
  DQ25_B  = M_L_CPU0_SB_DQ<25>
  VSS60  = GND
  DQS3_B_T  = M_L_CPU0_SB_DQS_DP<3>
  DQS3_B_C  = M_L_CPU0_SB_DQS_DN<3>
  VSS61  = GND
  DQ28_B  = M_L_CPU0_SB_DQ<28>
  VSS62  = GND
  DQ29_B  = M_L_CPU0_SB_DQ<29>
  VSS63  = GND
  RFU1  = NC
  VIN_BULK1  = P12V_MEM_CPU0
  VIN_BULK2  = P12V_MEM_CPU0
  \pwr_good||fail_n\  = PWRGD_CHL_CPU0_DIMM
  HAS  = PD_CHL_CPU0_DIMM_SAA
  RFU2  = NC
  RFU3  = NC
  VSS64  = GND
  DQ2_A  = M_L_CPU0_SA_DQ<2>
  VSS65  = GND
  DQ3_A  = M_L_CPU0_SA_DQ<3>
  VSS66  = GND
  \dqs5_a_c||tdqs5_a_c||dqs5_a_t||tdqs5_a_t\  = M_L_CPU0_SA_DQS_DN<5>
  \dqs5_a_t||tdqs5_a_t\  = M_L_CPU0_SA_DQS_DP<5>
  VSS67  = GND
  DQ6_A  = M_L_CPU0_SA_DQ<6>
  VSS68  = GND
  DQ7_A  = M_L_CPU0_SA_DQ<7>
  VSS69  = GND
  DQ10_A  = M_L_CPU0_SA_DQ<10>
  VSS70  = GND
  DQ11_A  = M_L_CPU0_SA_DQ<11>
  VSS71  = GND
  \dqs6_a_c||tdqs6_a_c||dqs6_a_t||tdqs6_a_t\  = M_L_CPU0_SA_DQS_DN<6>
  \dqs6_a_t||tdqs6_a_t\  = M_L_CPU0_SA_DQS_DP<6>
  VSS72  = GND
  DQ14_A  = M_L_CPU0_SA_DQ<14>
  VSS73  = GND
  DQ15_A  = M_L_CPU0_SA_DQ<15>
  VSS74  = GND
  DQ18_A  = M_L_CPU0_SA_DQ<18>
  VSS75  = GND
  DQ19_A  = M_L_CPU0_SA_DQ<19>
  VSS76  = GND
  \dqs7_a_c||tdqs7_a_c\  = M_L_CPU0_SA_DQS_DN<7>
  \dqs7_a_t||tdqs7_a_t\  = M_L_CPU0_SA_DQS_DP<7>
  VSS77  = GND
  DQ22_A  = M_L_CPU0_SA_DQ<22>
  VSS78  = GND
  DQ23_A  = M_L_CPU0_SA_DQ<23>
  VSS79  = GND
  DQ26_A  = M_L_CPU0_SA_DQ<26>
  VSS80  = GND
  DQ27_A  = M_L_CPU0_SA_DQ<27>
  VSS81  = GND
  \dqs8_a_c||tdqs8_a_c\  = M_L_CPU0_SA_DQS_DN<8>
  \dqs8_a_t||tdqs8_a_t\  = M_L_CPU0_SA_DQS_DP<8>
  VSS82  = GND
  DQ30_A  = M_L_CPU0_SA_DQ<30>
  VSS83  = GND
  DQ31_A  = M_L_CPU0_SA_DQ<31>
  VSS84  = GND
  CB2_A  = M_L_CPU0_SA_CB<2>
  VSS85  = GND
  CB3_A  = M_L_CPU0_SA_CB<3>
  VSS86  = GND
  \dqs9_a_c||tdqs9_a_c\  = M_L_CPU0_SA_DQS_DN<9>
  \dqs9_a_t||tdqs9_a_t\  = M_L_CPU0_SA_DQS_DP<9>
  VSS87  = GND
  CB6_A  = M_L_CPU0_SA_CB<6>
  VSS88  = GND
  CB7_A  = M_L_CPU0_SA_CB<7>
  VSS89  = GND
  RESET_N  = M_L_CPU0_RESET_N
  VSS90  = GND
  CS1_A_N  = M_L_CPU0_SA_CS_N<1>
  VSS91  = GND
  CA1_A  = M_L_CPU0_SA_CA<1>
  VSS92  = GND
  CA3_A  = M_L_CPU0_SA_CA<3>
  VSS93  = GND
  CA5_A  = M_L_CPU0_SA_CA<5>
  VSS94  = GND
  CK_T  = M_L_CPU0_CLK_DP<0>
  CK_C  = M_L_CPU0_CLK_DN<0>
  VSS95  = GND
  RFU4  = NC
  CA1_B  = M_L_CPU0_SB_CA<1>
  VSS96  = GND
  CA3_B  = M_L_CPU0_SB_CA<3>
  VSS97  = GND
  CA5_B  = M_L_CPU0_SB_CA<5>
  VSS98  = GND
  PAR_B  = M_L_CPU0_SB_PAR
  VSS99  = GND
  CS1_B_N  = M_L_CPU0_SB_CS_N<1>
  VSS100  = GND
  RFU5  = NC
  RFU6  = NC
  VSS101  = GND
  CB6_B  = M_L_CPU0_SB_CB<6>
  VSS102  = GND
  CB7_B  = M_L_CPU0_SB_CB<7>
  VSS103  = GND
  DQS4_B_C  = M_L_CPU0_SB_DQS_DN<4>
  DQS4_B_T  = M_L_CPU0_SB_DQS_DP<4>
  VSS104  = GND
  CB2_B  = M_L_CPU0_SB_CB<2>
  VSS105  = GND
  CB3_B  = M_L_CPU0_SB_CB<3>
  VSS106  = GND
  DQ2_B  = M_L_CPU0_SB_DQ<2>
  VSS107  = GND
  DQ3_B  = M_L_CPU0_SB_DQ<3>
  VSS108  = GND
  \dqs5_b_c||tdqs5_b_c\  = M_L_CPU0_SB_DQS_DN<5>
  \dqs5_b_t||tdqs5_b_t\  = M_L_CPU0_SB_DQS_DP<5>
  VSS109  = GND
  DQ6_B  = M_L_CPU0_SB_DQ<6>
  VSS110  = GND
  DQ7_B  = M_L_CPU0_SB_DQ<7>
  VSS111  = GND
  DQ10_B  = M_L_CPU0_SB_DQ<10>
  VSS112  = GND
  DQ11_B  = M_L_CPU0_SB_DQ<11>
  VSS113  = GND
  \dqs6_b_c||tdqs6_b_c\  = M_L_CPU0_SB_DQS_DN<6>
  \dqs6_b_t||tdqs6_b_t\  = M_L_CPU0_SB_DQS_DP<6>
  VSS114  = GND
  DQ14_B  = M_L_CPU0_SB_DQ<14>
  VSS115  = GND
  DQ15_B  = M_L_CPU0_SB_DQ<15>
  VSS116  = GND
  DQ18_B  = M_L_CPU0_SB_DQ<18>
  VSS117  = GND
  DQ19_B  = M_L_CPU0_SB_DQ<19>
  VSS118  = GND
  \dqs7_b_c||tdqs7_b_c\  = M_L_CPU0_SB_DQS_DN<7>
  \dqs7_b_t||tdqs7_b_t\  = M_L_CPU0_SB_DQS_DP<7>
  VSS119  = GND
  DQ22_B  = M_L_CPU0_SB_DQ<22>
  VSS120  = GND
  DQ23_B  = M_L_CPU0_SB_DQ<23>
  VSS121  = GND
  DQ26_B  = M_L_CPU0_SB_DQ<26>
  VSS122  = GND
  DQ27_B  = M_L_CPU0_SB_DQ<27>
  VSS123  = GND
  \dqs8_b_c||tdqs8_b_c\  = M_L_CPU0_SB_DQS_DN<8>
  \dqs8_b_t||tdqs8_b_t\  = M_L_CPU0_SB_DQS_DP<8>
  VSS124  = GND
  DQ30_B  = M_L_CPU0_SB_DQ<30>
  VSS125  = GND
  DQ31_B  = M_L_CPU0_SB_DQ<31>
  VSS126  = GND
  G1  = GND
  G2  = GND
  G3  = GND

(kicad_pcb
	(version 20260206)
	(generator "pcbnew")
	(generator_version "10.0")
	(general
		(thickness 1.6)
		(legacy_teardrops no)
	)
	(paper "A4")
	(title_block
		(title "04192023_DAF0TMB3IC0_F0TG_MB_C_brd_V02_OCP.brd")
		(comment 1 "Grand Teton / footprint 3721 of 8354 (J67), pads 139-184 of 291")
	)
	(layers
		(0 "F.Cu" signal "TOP")
		(4 "In1.Cu" signal "GND")
		(6 "In2.Cu" signal "IN1")
		(8 "In3.Cu" signal "GND1")
		(10 "In4.Cu" signal "IN2")
		(12 "In5.Cu" signal "GND2")
		(14 "In6.Cu" signal "IN3")
		(16 "In7.Cu" signal "GND3")
		(18 "In8.Cu" signal "VCC")
		(20 "In9.Cu" signal "VCC1")
		(22 "In10.Cu" signal "GND4")
		(24 "In11.Cu" signal "IN4")
		(26 "In12.Cu" signal "GND5")
		(28 "In13.Cu" signal "IN5")
		(30 "In14.Cu" signal "GND6")
		(32 "In15.Cu" signal "IN6")
		(34 "In16.Cu" signal "GND7")
		(2 "B.Cu" signal "BOTTOM")
		(9 "F.Adhes" user "F.Adhesive")
		(11 "B.Adhes" user "B.Adhesive")
		(13 "F.Paste" user "Package Geometry/Pastemask Top")
		(15 "B.Paste" user "Package Geometry/Pastemask Bottom")
		(5 "F.SilkS" user "Ref Des/Silkscreen Top")
		(7 "B.SilkS" user "Ref Des/Silkscreen Bottom")
		(1 "F.Mask" user "Board Geometry/Soldermask Top")
		(3 "B.Mask" user "Board Geometry/Soldermask Bottom")
		(17 "Dwgs.User" user "User.Drawings")
		(19 "Cmts.User" user "User.Comments")
		(21 "Eco1.User" user "User.Eco1")
		(23 "Eco2.User" user "User.Eco2")
		(25 "Edge.Cuts" user "Board Geometry/Outline")
		(27 "Margin" user)
		(31 "F.CrtYd" user "Package Geometry/Place Bound Top")
		(29 "B.CrtYd" user "Package Geometry/Place Bound Bottom")
		(35 "F.Fab" user "Ref Des/Assembly Top")
		(33 "B.Fab" user "Ref Des/Assembly Bottom")
	)
	(footprint ""
		(layer "F.Cu")
		(at 452.138034 -255.560068 180)
		(property "Reference" "J67"
			(at 2.380488 -81.709768 0)
			(unlocked yes)
			(layer "F.SilkS")
			(effects
				(font
					(size 0.7874 0.5842)
					(thickness 0.1524)
				)
			)
		)
		(property "Value" ""
			(at 0 0 180)
			(layer "F.Fab")
			(effects
				(font
					(size 1.27 1.27)
				)
			)
		)
		(duplicate_pad_numbers_are_jumpers no)
		(pad "139" smd rect
			(at -2.050034 59.075066 90)
			(size 0.519938 1.4986)
			(layers "F.Cu" "F.Mask" "F.Paste")
			(net "GND")
		)
		(pad "140" smd rect
			(at -2.050034 59.92495 90)
			(size 0.519938 1.4986)
			(layers "F.Cu" "F.Mask" "F.Paste")
			(net "M_L_CPU0_SB_DQ<28>")
		)
		(pad "141" smd rect
			(at -2.050034 60.775088 90)
			(size 0.519938 1.4986)
			(layers "F.Cu" "F.Mask" "F.Paste")
			(net "GND")
		)
		(pad "142" smd rect
			(at -2.050034 61.624972 90)
			(size 0.519938 1.4986)
			(layers "F.Cu" "F.Mask" "F.Paste")
			(net "M_L_CPU0_SB_DQ<29>")
		)
		(pad "143" smd rect
			(at -2.050034 62.47511 90)
			(size 0.519938 1.4986)
			(layers "F.Cu" "F.Mask" "F.Paste")
			(net "GND")
		)
		(pad "144" smd rect
			(at -2.050034 63.324994 90)
			(size 0.519938 1.4986)
			(layers "F.Cu" "F.Mask" "F.Paste")
			(net "Net_2404")
		)
		(pad "145" smd rect
			(at 2.050034 -63.324994 90)
			(size 0.519938 1.4986)
			(layers "F.Cu" "F.Mask" "F.Paste")
			(net "P12V_MEM_CPU0")
		)
		(pad "146" smd rect
			(at 2.050034 -62.47511 90)
			(size 0.519938 1.4986)
			(layers "F.Cu" "F.Mask" "F.Paste")
			(net "P12V_MEM_CPU0")
		)
		(pad "147" smd rect
			(at 2.050034 -61.624972 90)
			(size 0.519938 1.4986)
			(layers "F.Cu" "F.Mask" "F.Paste")
			(net "PWRGD_CHL_CPU0_DIMM")
		)
		(pad "148" smd rect
			(at 2.050034 -60.775088 90)
			(size 0.519938 1.4986)
			(layers "F.Cu" "F.Mask" "F.Paste")
			(net "PD_CHL_CPU0_DIMM_SAA")
		)
		(pad "149" smd rect
			(at 2.050034 -59.92495 90)
			(size 0.519938 1.4986)
			(layers "F.Cu" "F.Mask" "F.Paste")
			(net "Net_2405")
		)
		(pad "150" smd rect
			(at 2.050034 -59.075066 90)
			(size 0.519938 1.4986)
			(layers "F.Cu" "F.Mask" "F.Paste")
			(net "Net_2406")
		)
		(pad "151" smd rect
			(at 2.050034 -58.224928 90)
			(size 0.519938 1.4986)
			(layers "F.Cu" "F.Mask" "F.Paste")
			(net "GND")
		)
		(pad "152" smd rect
			(at 2.050034 -57.375044 90)
			(size 0.519938 1.4986)
			(layers "F.Cu" "F.Mask" "F.Paste")
			(net "M_L_CPU0_SA_DQ<2>")
		)
		(pad "153" smd rect
			(at 2.050034 -56.524906 90)
			(size 0.519938 1.4986)
			(layers "F.Cu" "F.Mask" "F.Paste")
			(net "GND")
		)
		(pad "154" smd rect
			(at 2.050034 -55.675022 90)
			(size 0.519938 1.4986)
			(layers "F.Cu" "F.Mask" "F.Paste")
			(net "M_L_CPU0_SA_DQ<3>")
		)
		(pad "155" smd rect
			(at 2.050034 -54.824884 90)
			(size 0.519938 1.4986)
			(layers "F.Cu" "F.Mask" "F.Paste")
			(net "GND")
		)
		(pad "156" smd rect
			(at 2.050034 -53.975 90)
			(size 0.519938 1.4986)
			(layers "F.Cu" "F.Mask" "F.Paste")
			(net "M_L_CPU0_SA_DQS_DN<5>")
		)
		(pad "157" smd rect
			(at 2.050034 -53.125116 90)
			(size 0.519938 1.4986)
			(layers "F.Cu" "F.Mask" "F.Paste")
			(net "M_L_CPU0_SA_DQS_DP<5>")
		)
		(pad "158" smd rect
			(at 2.050034 -52.274978 90)
			(size 0.519938 1.4986)
			(layers "F.Cu" "F.Mask" "F.Paste")
			(net "GND")
		)
		(pad "159" smd rect
			(at 2.050034 -51.425094 90)
			(size 0.519938 1.4986)
			(layers "F.Cu" "F.Mask" "F.Paste")
			(net "M_L_CPU0_SA_DQ<6>")
		)
		(pad "160" smd rect
			(at 2.050034 -50.574956 90)
			(size 0.519938 1.4986)
			(layers "F.Cu" "F.Mask" "F.Paste")
			(net "GND")
		)
		(pad "161" smd rect
			(at 2.050034 -49.725072 90)
			(size 0.519938 1.4986)
			(layers "F.Cu" "F.Mask" "F.Paste")
			(net "M_L_CPU0_SA_DQ<7>")
		)
		(pad "162" smd rect
			(at 2.050034 -48.874934 90)
			(size 0.519938 1.4986)
			(layers "F.Cu" "F.Mask" "F.Paste")
			(net "GND")
		)
		(pad "163" smd rect
			(at 2.050034 -48.02505 90)
			(size 0.519938 1.4986)
			(layers "F.Cu" "F.Mask" "F.Paste")
			(net "M_L_CPU0_SA_DQ<10>")
		)
		(pad "164" smd rect
			(at 2.050034 -47.174912 90)
			(size 0.519938 1.4986)
			(layers "F.Cu" "F.Mask" "F.Paste")
			(net "GND")
		)
		(pad "165" smd rect
			(at 2.050034 -46.325028 90)
			(size 0.519938 1.4986)
			(layers "F.Cu" "F.Mask" "F.Paste")
			(net "M_L_CPU0_SA_DQ<11>")
		)
		(pad "166" smd rect
			(at 2.050034 -45.47489 90)
			(size 0.519938 1.4986)
			(layers "F.Cu" "F.Mask" "F.Paste")
			(net "GND")
		)
		(pad "167" smd rect
			(at 2.050034 -44.625006 90)
			(size 0.519938 1.4986)
			(layers "F.Cu" "F.Mask" "F.Paste")
			(net "M_L_CPU0_SA_DQS_DN<6>")
		)
		(pad "168" smd rect
			(at 2.050034 -43.775122 90)
			(size 0.519938 1.4986)
			(layers "F.Cu" "F.Mask" "F.Paste")
			(net "M_L_CPU0_SA_DQS_DP<6>")
		)
		(pad "169" smd rect
			(at 2.050034 -42.924984 90)
			(size 0.519938 1.4986)
			(layers "F.Cu" "F.Mask" "F.Paste")
			(net "GND")
		)
		(pad "170" smd rect
			(at 2.050034 -42.0751 90)
			(size 0.519938 1.4986)
			(layers "F.Cu" "F.Mask" "F.Paste")
			(net "M_L_CPU0_SA_DQ<14>")
		)
		(pad "171" smd rect
			(at 2.050034 -41.224962 90)
			(size 0.519938 1.4986)
			(layers "F.Cu" "F.Mask" "F.Paste")
			(net "GND")
		)
		(pad "172" smd rect
			(at 2.050034 -40.375078 90)
			(size 0.519938 1.4986)
			(layers "F.Cu" "F.Mask" "F.Paste")
			(net "M_L_CPU0_SA_DQ<15>")
		)
		(pad "173" smd rect
			(at 2.050034 -39.52494 90)
			(size 0.519938 1.4986)
			(layers "F.Cu" "F.Mask" "F.Paste")
			(net "GND")
		)
		(pad "174" smd rect
			(at 2.050034 -38.675056 90)
			(size 0.519938 1.4986)
			(layers "F.Cu" "F.Mask" "F.Paste")
			(net "M_L_CPU0_SA_DQ<18>")
		)
		(pad "175" smd rect
			(at 2.050034 -37.824918 90)
			(size 0.519938 1.4986)
			(layers "F.Cu" "F.Mask" "F.Paste")
			(net "GND")
		)
		(pad "176" smd rect
			(at 2.050034 -36.975034 90)
			(size 0.519938 1.4986)
			(layers "F.Cu" "F.Mask" "F.Paste")
			(net "M_L_CPU0_SA_DQ<19>")
		)
		(pad "177" smd rect
			(at 2.050034 -36.124896 90)
			(size 0.519938 1.4986)
			(layers "F.Cu" "F.Mask" "F.Paste")
			(net "GND")
		)
		(pad "178" smd rect
			(at 2.050034 -35.275012 90)
			(size 0.519938 1.4986)
			(layers "F.Cu" "F.Mask" "F.Paste")
			(net "M_L_CPU0_SA_DQS_DN<7>")
		)
		(pad "179" smd rect
			(at 2.050034 -34.425128 90)
			(size 0.519938 1.4986)
			(layers "F.Cu" "F.Mask" "F.Paste")
			(net "M_L_CPU0_SA_DQS_DP<7>")
		)
		(pad "180" smd rect
			(at 2.050034 -33.57499 90)
			(size 0.519938 1.4986)
			(layers "F.Cu" "F.Mask" "F.Paste")
			(net "GND")
		)
		(pad "181" smd rect
			(at 2.050034 -32.725106 90)
			(size 0.519938 1.4986)
			(layers "F.Cu" "F.Mask" "F.Paste")
			(net "M_L_CPU0_SA_DQ<22>")
		)
		(pad "182" smd rect
			(at 2.050034 -31.874968 90)
			(size 0.519938 1.4986)
			(layers "F.Cu" "F.Mask" "F.Paste")
			(net "GND")
		)
		(pad "183" smd rect
			(at 2.050034 -31.025084 90)
			(size 0.519938 1.4986)
			(layers "F.Cu" "F.Mask" "F.Paste")
			(net "M_L_CPU0_SA_DQ<23>")
		)
		(pad "184" smd rect
			(at 2.050034 -30.174946 90)
			(size 0.519938 1.4986)
			(layers "F.Cu" "F.Mask" "F.Paste")
			(net "GND")
		)
	)
)
